(kicad_pcb
	(version 20260206)
	(generator "pcbnew")
	(generator_version "10.0")
	(general
		(thickness 1.6)
		(legacy_teardrops no)
	)
	(paper "A4")
	(title_block
		(title "12092022_DA0F0TFB6D0_F0T_FAN_BOARD_MP5048_D_brd_v02_OCP.brd")
		(comment 1 "Grand Teton / footprints 122-127 of 924")
	)
	(layers
		(0 "F.Cu" signal "TOP")
		(4 "In1.Cu" signal "GND")
		(6 "In2.Cu" signal "IN1")
		(8 "In3.Cu" signal "IN2")
		(10 "In4.Cu" signal "GND1")
		(2 "B.Cu" signal "BOTTOM")
		(9 "F.Adhes" user "F.Adhesive")
		(11 "B.Adhes" user "B.Adhesive")
		(13 "F.Paste" user "Package Geometry/Pastemask Top")
		(15 "B.Paste" user "Package Geometry/Pastemask Bottom")
		(5 "F.SilkS" user "Ref Des/Silkscreen Top")
		(7 "B.SilkS" user "Ref Des/Silkscreen Bottom")
		(1 "F.Mask" user "Board Geometry/Soldermask Top")
		(3 "B.Mask" user "Board Geometry/Soldermask Bottom")
		(17 "Dwgs.User" user "User.Drawings")
		(19 "Cmts.User" user "User.Comments")
		(21 "Eco1.User" user "User.Eco1")
		(23 "Eco2.User" user "User.Eco2")
		(25 "Edge.Cuts" user "Board Geometry/Outline")
		(27 "Margin" user)
		(31 "F.CrtYd" user "Package Geometry/Place Bound Top")
		(29 "B.CrtYd" user "Package Geometry/Place Bound Bottom")
		(35 "F.Fab" user "Ref Des/Assembly Top")
		(33 "B.Fab" user "Ref Des/Assembly Bottom")
	)
	(footprint ""
		(layer "F.Cu")
		(at 14.351 -21.384768)
		(property "Reference" "R5132"
			(at 0 0 0)
			(layer "F.SilkS")
			(hide yes)
			(effects
				(font
					(size 1.27 1.27)
				)
			)
		)
		(property "Value" ""
			(at 0 0 0)
			(layer "F.Fab")
			(effects
				(font
					(size 1.27 1.27)
				)
			)
		)
		(duplicate_pad_numbers_are_jumpers no)
		(fp_line
			(start -0.7874 -0.4064)
			(end 0.7874 -0.4064)
			(stroke
				(width 0.1524)
				(type default)
			)
			(layer "F.SilkS")
		)
		(fp_line
			(start -0.7874 0.4064)
			(end -0.7874 -0.4064)
			(stroke
				(width 0.1524)
				(type default)
			)
			(layer "F.SilkS")
		)
		(fp_line
			(start 0.7874 -0.4064)
			(end 0.7874 0.4064)
			(stroke
				(width 0.1524)
				(type default)
			)
			(layer "F.SilkS")
		)
		(fp_line
			(start 0.7874 0.4064)
			(end -0.7874 0.4064)
			(stroke
				(width 0.1524)
				(type default)
			)
			(layer "F.SilkS")
		)
		(fp_line
			(start -0.67945 -0.305054)
			(end -0.12065 -0.305054)
			(stroke
				(width 0.1)
				(type default)
			)
			(layer "F.Fab")
		)
		(fp_line
			(start -0.67945 0.3048)
			(end -0.67945 -0.305054)
			(stroke
				(width 0.1)
				(type default)
			)
			(layer "F.Fab")
		)
		(fp_line
			(start -0.12065 -0.305054)
			(end -0.12065 -0.2794)
			(stroke
				(width 0.1)
				(type default)
			)
			(layer "F.Fab")
		)
		(fp_line
			(start -0.12065 -0.2794)
			(end 0.12065 -0.2794)
			(stroke
				(width 0.1)
				(type default)
			)
			(layer "F.Fab")
		)
		(fp_line
			(start -0.12065 0.2794)
			(end -0.12065 0.3048)
			(stroke
				(width 0.1)
				(type default)
			)
			(layer "F.Fab")
		)
		(fp_line
			(start -0.12065 0.3048)
			(end -0.67945 0.3048)
			(stroke
				(width 0.1)
				(type default)
			)
			(layer "F.Fab")
		)
		(fp_line
			(start 0.120396 0.2794)
			(end -0.12065 0.2794)
			(stroke
				(width 0.1)
				(type default)
			)
			(layer "F.Fab")
		)
		(fp_line
			(start 0.120396 0.3048)
			(end 0.120396 0.2794)
			(stroke
				(width 0.1)
				(type default)
			)
			(layer "F.Fab")
		)
		(fp_line
			(start 0.12065 -0.3048)
			(end 0.67945 -0.3048)
			(stroke
				(width 0.1)
				(type default)
			)
			(layer "F.Fab")
		)
		(fp_line
			(start 0.12065 -0.2794)
			(end 0.12065 -0.3048)
			(stroke
				(width 0.1)
				(type default)
			)
			(layer "F.Fab")
		)
		(fp_line
			(start 0.67945 -0.3048)
			(end 0.67945 0.3048)
			(stroke
				(width 0.1)
				(type default)
			)
			(layer "F.Fab")
		)
		(fp_line
			(start 0.67945 0.3048)
			(end 0.120396 0.3048)
			(stroke
				(width 0.1)
				(type default)
			)
			(layer "F.Fab")
		)
		(pad "1" smd circle
			(at -0.40005 0)
			(size 0 0)
			(layers "F.Cu" "F.Mask" "F.Paste")
			(net "SMB_FAN4_SDA_R")
		)
		(pad "2" smd circle
			(at 0.40005 0)
			(size 0 0)
			(layers "F.Cu" "F.Mask" "F.Paste")
			(net "SMB_FAN4_SDA")
		)
	)
	(footprint ""
		(layer "F.Cu")
		(at 23.114 -141.605 -90)
		(property "Reference" "R5277"
			(at 0 0 270)
			(layer "F.SilkS")
			(hide yes)
			(effects
				(font
					(size 1.27 1.27)
				)
			)
		)
		(property "Value" ""
			(at 0 0 270)
			(layer "F.Fab")
			(effects
				(font
					(size 1.27 1.27)
				)
			)
		)
		(duplicate_pad_numbers_are_jumpers no)
		(fp_line
			(start -0.7874 0.4064)
			(end -0.7874 -0.4064)
			(stroke
				(width 0.1524)
				(type default)
			)
			(layer "F.SilkS")
		)
		(fp_line
			(start 0.7874 0.4064)
			(end -0.7874 0.4064)
			(stroke
				(width 0.1524)
				(type default)
			)
			(layer "F.SilkS")
		)
		(fp_line
			(start -0.7874 -0.4064)
			(end 0.7874 -0.4064)
			(stroke
				(width 0.1524)
				(type default)
			)
			(layer "F.SilkS")
		)
		(fp_line
			(start 0.7874 -0.4064)
			(end 0.7874 0.4064)
			(stroke
				(width 0.1524)
				(type default)
			)
			(layer "F.SilkS")
		)
		(fp_line
			(start -0.67945 0.3048)
			(end -0.67945 -0.305054)
			(stroke
				(width 0.1)
				(type default)
			)
			(layer "F.Fab")
		)
		(fp_line
			(start -0.12065 0.3048)
			(end -0.67945 0.3048)
			(stroke
				(width 0.1)
				(type default)
			)
			(layer "F.Fab")
		)
		(fp_line
			(start 0.120396 0.3048)
			(end 0.120396 0.2794)
			(stroke
				(width 0.1)
				(type default)
			)
			(layer "F.Fab")
		)
		(fp_line
			(start 0.67945 0.3048)
			(end 0.120396 0.3048)
			(stroke
				(width 0.1)
				(type default)
			)
			(layer "F.Fab")
		)
		(fp_line
			(start -0.12065 0.2794)
			(end -0.12065 0.3048)
			(stroke
				(width 0.1)
				(type default)
			)
			(layer "F.Fab")
		)
		(fp_line
			(start 0.120396 0.2794)
			(end -0.12065 0.2794)
			(stroke
				(width 0.1)
				(type default)
			)
			(layer "F.Fab")
		)
		(fp_line
			(start -0.12065 -0.2794)
			(end 0.12065 -0.2794)
			(stroke
				(width 0.1)
				(type default)
			)
			(layer "F.Fab")
		)
		(fp_line
			(start 0.12065 -0.2794)
			(end 0.12065 -0.3048)
			(stroke
				(width 0.1)
				(type default)
			)
			(layer "F.Fab")
		)
		(fp_line
			(start 0.12065 -0.3048)
			(end 0.67945 -0.3048)
			(stroke
				(width 0.1)
				(type default)
			)
			(layer "F.Fab")
		)
		(fp_line
			(start 0.67945 -0.3048)
			(end 0.67945 0.3048)
			(stroke
				(width 0.1)
				(type default)
			)
			(layer "F.Fab")
		)
		(fp_line
			(start -0.67945 -0.305054)
			(end -0.12065 -0.305054)
			(stroke
				(width 0.1)
				(type default)
			)
			(layer "F.Fab")
		)
		(fp_line
			(start -0.12065 -0.305054)
			(end -0.12065 -0.2794)
			(stroke
				(width 0.1)
				(type default)
			)
			(layer "F.Fab")
		)
		(pad "1" smd circle
			(at -0.40005 0 270)
			(size 0 0)
			(layers "F.Cu" "F.Mask" "F.Paste")
			(net "SMB_FAN0_R_SDA")
		)
		(pad "2" smd circle
			(at 0.40005 0 270)
			(size 0 0)
			(layers "F.Cu" "F.Mask" "F.Paste")
			(net "P3V3_AUX")
		)
	)
	(footprint ""
		(layer "F.Cu")
		(at 33.401 -16.51 180)
		(property "Reference" "R5327"
			(at 0 0 180)
			(layer "F.SilkS")
			(hide yes)
			(effects
				(font
					(size 1.27 1.27)
				)
			)
		)
		(property "Value" ""
			(at 0 0 180)
			(layer "F.Fab")
			(effects
				(font
					(size 1.27 1.27)
				)
			)
		)
		(duplicate_pad_numbers_are_jumpers no)
		(fp_line
			(start 0.7874 0.4064)
			(end -0.7874 0.4064)
			(stroke
				(width 0.1524)
				(type default)
			)
			(layer "F.SilkS")
		)
		(fp_line
			(start 0.7874 -0.4064)
			(end 0.7874 0.4064)
			(stroke
				(width 0.1524)
				(type default)
			)
			(layer "F.SilkS")
		)
		(fp_line
			(start -0.7874 0.4064)
			(end -0.7874 -0.4064)
			(stroke
				(width 0.1524)
				(type default)
			)
			(layer "F.SilkS")
		)
		(fp_line
			(start -0.7874 -0.4064)
			(end 0.7874 -0.4064)
			(stroke
				(width 0.1524)
				(type default)
			)
			(layer "F.SilkS")
		)
		(fp_line
			(start 0.67945 0.3048)
			(end 0.120396 0.3048)
			(stroke
				(width 0.1)
				(type default)
			)
			(layer "F.Fab")
		)
		(fp_line
			(start 0.67945 -0.3048)
			(end 0.67945 0.3048)
			(stroke
				(width 0.1)
				(type default)
			)
			(layer "F.Fab")
		)
		(fp_line
			(start 0.12065 -0.2794)
			(end 0.12065 -0.3048)
			(stroke
				(width 0.1)
				(type default)
			)
			(layer "F.Fab")
		)
		(fp_line
			(start 0.12065 -0.3048)
			(end 0.67945 -0.3048)
			(stroke
				(width 0.1)
				(type default)
			)
			(layer "F.Fab")
		)
		(fp_line
			(start 0.120396 0.3048)
			(end 0.120396 0.2794)
			(stroke
				(width 0.1)
				(type default)
			)
			(layer "F.Fab")
		)
		(fp_line
			(start 0.120396 0.2794)
			(end -0.12065 0.2794)
			(stroke
				(width 0.1)
				(type default)
			)
			(layer "F.Fab")
		)
		(fp_line
			(start -0.12065 0.3048)
			(end -0.67945 0.3048)
			(stroke
				(width 0.1)
				(type default)
			)
			(layer "F.Fab")
		)
		(fp_line
			(start -0.12065 0.2794)
			(end -0.12065 0.3048)
			(stroke
				(width 0.1)
				(type default)
			)
			(layer "F.Fab")
		)
		(fp_line
			(start -0.12065 -0.2794)
			(end 0.12065 -0.2794)
			(stroke
				(width 0.1)
				(type default)
			)
			(layer "F.Fab")
		)
		(fp_line
			(start -0.12065 -0.305054)
			(end -0.12065 -0.2794)
			(stroke
				(width 0.1)
				(type default)
			)
			(layer "F.Fab")
		)
		(fp_line
			(start -0.67945 0.3048)
			(end -0.67945 -0.305054)
			(stroke
				(width 0.1)
				(type default)
			)
			(layer "F.Fab")
		)
		(fp_line
			(start -0.67945 -0.305054)
			(end -0.12065 -0.305054)
			(stroke
				(width 0.1)
				(type default)
			)
			(layer "F.Fab")
		)
		(pad "1" smd rect
			(at -0.40005 0)
			(size 0.4572 0.508)
			(layers "F.Cu" "F.Mask" "F.Paste")
			(net "FAN_3_TACH_OL_R")
		)
		(pad "2" smd rect
			(at 0.40005 0)
			(size 0.4572 0.508)
			(layers "F.Cu" "F.Mask" "F.Paste")
			(net "FAN_3_TACH_OL")
		)
	)
	(footprint ""
		(layer "F.Cu")
		(at 48.26 -133.731 180)
		(property "Reference" "R5558"
			(at 0 0 180)
			(layer "F.SilkS")
			(hide yes)
			(effects
				(font
					(size 1.27 1.27)
				)
			)
		)
		(property "Value" ""
			(at 0 0 180)
			(layer "F.Fab")
			(effects
				(font
					(size 1.27 1.27)
				)
			)
		)
		(duplicate_pad_numbers_are_jumpers no)
		(fp_line
			(start 0.7874 0.4064)
			(end -0.7874 0.4064)
			(stroke
				(width 0.1524)
				(type default)
			)
			(layer "F.SilkS")
		)
		(fp_line
			(start 0.7874 -0.4064)
			(end 0.7874 0.4064)
			(stroke
				(width 0.1524)
				(type default)
			)
			(layer "F.SilkS")
		)
		(fp_line
			(start -0.7874 0.4064)
			(end -0.7874 -0.4064)
			(stroke
				(width 0.1524)
				(type default)
			)
			(layer "F.SilkS")
		)
		(fp_line
			(start -0.7874 -0.4064)
			(end 0.7874 -0.4064)
			(stroke
				(width 0.1524)
				(type default)
			)
			(layer "F.SilkS")
		)
		(fp_line
			(start 0.67945 0.3048)
			(end 0.120396 0.3048)
			(stroke
				(width 0.1)
				(type default)
			)
			(layer "F.Fab")
		)
		(fp_line
			(start 0.67945 -0.3048)
			(end 0.67945 0.3048)
			(stroke
				(width 0.1)
				(type default)
			)
			(layer "F.Fab")
		)
		(fp_line
			(start 0.12065 -0.2794)
			(end 0.12065 -0.3048)
			(stroke
				(width 0.1)
				(type default)
			)
			(layer "F.Fab")
		)
		(fp_line
			(start 0.12065 -0.3048)
			(end 0.67945 -0.3048)
			(stroke
				(width 0.1)
				(type default)
			)
			(layer "F.Fab")
		)
		(fp_line
			(start 0.120396 0.3048)
			(end 0.120396 0.2794)
			(stroke
				(width 0.1)
				(type default)
			)
			(layer "F.Fab")
		)
		(fp_line
			(start 0.120396 0.2794)
			(end -0.12065 0.2794)
			(stroke
				(width 0.1)
				(type default)
			)
			(layer "F.Fab")
		)
		(fp_line
			(start -0.12065 0.3048)
			(end -0.67945 0.3048)
			(stroke
				(width 0.1)
				(type default)
			)
			(layer "F.Fab")
		)
		(fp_line
			(start -0.12065 0.2794)
			(end -0.12065 0.3048)
			(stroke
				(width 0.1)
				(type default)
			)
			(layer "F.Fab")
		)
		(fp_line
			(start -0.12065 -0.2794)
			(end 0.12065 -0.2794)
			(stroke
				(width 0.1)
				(type default)
			)
			(layer "F.Fab")
		)
		(fp_line
			(start -0.12065 -0.305054)
			(end -0.12065 -0.2794)
			(stroke
				(width 0.1)
				(type default)
			)
			(layer "F.Fab")
		)
		(fp_line
			(start -0.67945 0.3048)
			(end -0.67945 -0.305054)
			(stroke
				(width 0.1)
				(type default)
			)
			(layer "F.Fab")
		)
		(fp_line
			(start -0.67945 -0.305054)
			(end -0.12065 -0.305054)
			(stroke
				(width 0.1)
				(type default)
			)
			(layer "F.Fab")
		)
		(pad "1" smd circle
			(at -0.40005 0 180)
			(size 0 0)
			(layers "F.Cu" "F.Mask" "F.Paste")
			(net "SMB_PDBV_FAN_SCL")
		)
		(pad "2" smd circle
			(at 0.40005 0 180)
			(size 0 0)
			(layers "F.Cu" "F.Mask" "F.Paste")
			(net "SMB_PDBV_FAN_R_U403_SCL")
		)
	)
	(footprint ""
		(layer "F.Cu")
		(at 25.527 -180.594 180)
		(property "Reference" "C2080"
			(at 0 0 180)
			(layer "F.SilkS")
			(hide yes)
			(effects
				(font
					(size 1.27 1.27)
				)
			)
		)
		(property "Value" ""
			(at 0 0 180)
			(layer "F.Fab")
			(effects
				(font
					(size 1.27 1.27)
				)
			)
		)
		(duplicate_pad_numbers_are_jumpers no)
		(fp_line
			(start 0.7874 0.4064)
			(end -0.7874 0.4064)
			(stroke
				(width 0.1524)
				(type default)
			)
			(layer "F.SilkS")
		)
		(fp_line
			(start 0.7874 -0.4064)
			(end 0.7874 0.4064)
			(stroke
				(width 0.1524)
				(type default)
			)
			(layer "F.SilkS")
		)
		(fp_line
			(start -0.7874 0.4064)
			(end -0.7874 -0.4064)
			(stroke
				(width 0.1524)
				(type default)
			)
			(layer "F.SilkS")
		)
		(fp_line
			(start -0.7874 -0.4064)
			(end 0.7874 -0.4064)
			(stroke
				(width 0.1524)
				(type default)
			)
			(layer "F.SilkS")
		)
		(fp_line
			(start 0.67945 0.3048)
			(end 0.120396 0.3048)
			(stroke
				(width 0.1)
				(type default)
			)
			(layer "F.Fab")
		)
		(fp_line
			(start 0.67945 -0.3048)
			(end 0.67945 0.3048)
			(stroke
				(width 0.1)
				(type default)
			)
			(layer "F.Fab")
		)
		(fp_line
			(start 0.12065 -0.2794)
			(end 0.12065 -0.3048)
			(stroke
				(width 0.1)
				(type default)
			)
			(layer "F.Fab")
		)
		(fp_line
			(start 0.12065 -0.3048)
			(end 0.67945 -0.3048)
			(stroke
				(width 0.1)
				(type default)
			)
			(layer "F.Fab")
		)
		(fp_line
			(start 0.120396 0.3048)
			(end 0.120396 0.2794)
			(stroke
				(width 0.1)
				(type default)
			)
			(layer "F.Fab")
		)
		(fp_line
			(start 0.120396 0.2794)
			(end -0.12065 0.2794)
			(stroke
				(width 0.1)
				(type default)
			)
			(layer "F.Fab")
		)
		(fp_line
			(start -0.12065 0.3048)
			(end -0.67945 0.3048)
			(stroke
				(width 0.1)
				(type default)
			)
			(layer "F.Fab")
		)
		(fp_line
			(start -0.12065 0.2794)
			(end -0.12065 0.3048)
			(stroke
				(width 0.1)
				(type default)
			)
			(layer "F.Fab")
		)
		(fp_line
			(start -0.12065 -0.2794)
			(end 0.12065 -0.2794)
			(stroke
				(width 0.1)
				(type default)
			)
			(layer "F.Fab")
		)
		(fp_line
			(start -0.12065 -0.305054)
			(end -0.12065 -0.2794)
			(stroke
				(width 0.1)
				(type default)
			)
			(layer "F.Fab")
		)
		(fp_line
			(start -0.67945 0.3048)
			(end -0.67945 -0.305054)
			(stroke
				(width 0.1)
				(type default)
			)
			(layer "F.Fab")
		)
		(fp_line
			(start -0.67945 -0.305054)
			(end -0.12065 -0.305054)
			(stroke
				(width 0.1)
				(type default)
			)
			(layer "F.Fab")
		)
		(pad "1" smd circle
			(at -0.40005 0 180)
			(size 0 0)
			(layers "F.Cu" "F.Mask" "F.Paste")
			(net "P52V_FAN_1_BUFF_EN_R")
		)
		(pad "2" smd circle
			(at 0.40005 0 180)
			(size 0 0)
			(layers "F.Cu" "F.Mask" "F.Paste")
			(net "GND")
		)
	)
	(footprint ""
		(layer "F.Cu")
		(at 19.558 -26.924 -90)
		(property "Reference" "R4990"
			(at 0 0 270)
			(layer "F.SilkS")
			(hide yes)
			(effects
				(font
					(size 1.27 1.27)
				)
			)
		)
		(property "Value" ""
			(at 0 0 270)
			(layer "F.Fab")
			(effects
				(font
					(size 1.27 1.27)
				)
			)
		)
		(duplicate_pad_numbers_are_jumpers no)
		(fp_line
			(start -0.7874 0.4064)
			(end -0.7874 -0.4064)
			(stroke
				(width 0.1524)
				(type default)
			)
			(layer "F.SilkS")
		)
		(fp_line
			(start 0.7874 0.4064)
			(end -0.7874 0.4064)
			(stroke
				(width 0.1524)
				(type default)
			)
			(layer "F.SilkS")
		)
		(fp_line
			(start -0.7874 -0.4064)
			(end 0.7874 -0.4064)
			(stroke
				(width 0.1524)
				(type default)
			)
			(layer "F.SilkS")
		)
		(fp_line
			(start 0.7874 -0.4064)
			(end 0.7874 0.4064)
			(stroke
				(width 0.1524)
				(type default)
			)
			(layer "F.SilkS")
		)
		(fp_line
			(start -0.67945 0.3048)
			(end -0.67945 -0.305054)
			(stroke
				(width 0.1)
				(type default)
			)
			(layer "F.Fab")
		)
		(fp_line
			(start -0.12065 0.3048)
			(end -0.67945 0.3048)
			(stroke
				(width 0.1)
				(type default)
			)
			(layer "F.Fab")
		)
		(fp_line
			(start 0.120396 0.3048)
			(end 0.120396 0.2794)
			(stroke
				(width 0.1)
				(type default)
			)
			(layer "F.Fab")
		)
		(fp_line
			(start 0.67945 0.3048)
			(end 0.120396 0.3048)
			(stroke
				(width 0.1)
				(type default)
			)
			(layer "F.Fab")
		)
		(fp_line
			(start -0.12065 0.2794)
			(end -0.12065 0.3048)
			(stroke
				(width 0.1)
				(type default)
			)
			(layer "F.Fab")
		)
		(fp_line
			(start 0.120396 0.2794)
			(end -0.12065 0.2794)
			(stroke
				(width 0.1)
				(type default)
			)
			(layer "F.Fab")
		)
		(fp_line
			(start -0.12065 -0.2794)
			(end 0.12065 -0.2794)
			(stroke
				(width 0.1)
				(type default)
			)
			(layer "F.Fab")
		)
		(fp_line
			(start 0.12065 -0.2794)
			(end 0.12065 -0.3048)
			(stroke
				(width 0.1)
				(type default)
			)
			(layer "F.Fab")
		)
		(fp_line
			(start 0.12065 -0.3048)
			(end 0.67945 -0.3048)
			(stroke
				(width 0.1)
				(type default)
			)
			(layer "F.Fab")
		)
		(fp_line
			(start 0.67945 -0.3048)
			(end 0.67945 0.3048)
			(stroke
				(width 0.1)
				(type default)
			)
			(layer "F.Fab")
		)
		(fp_line
			(start -0.67945 -0.305054)
			(end -0.12065 -0.305054)
			(stroke
				(width 0.1)
				(type default)
			)
			(layer "F.Fab")
		)
		(fp_line
			(start -0.12065 -0.305054)
			(end -0.12065 -0.2794)
			(stroke
				(width 0.1)
				(type default)
			)
			(layer "F.Fab")
		)
		(pad "1" smd circle
			(at -0.40005 0 270)
			(size 0 0)
			(layers "F.Cu" "F.Mask" "F.Paste")
			(net "P3V3_AUX")
		)
		(pad "2" smd circle
			(at 0.40005 0 270)
			(size 0 0)
			(layers "F.Cu" "F.Mask" "F.Paste")
			(net "FAN_4_OK_R_LED")
		)
	)
)
